(kicad_pcb
	(version 20260206)
	(generator "pcbnew")
	(generator_version "10.0")
	(general
		(thickness 1.6)
		(legacy_teardrops no)
	)
	(paper "A4")
	(title_block
		(title "01162023_DA0F0TEBIF0_F0T_Expander_BD_F_brd_V02_OCP.brd")
		(comment 1 "Grand Teton / footprints 6385-6390 of 9728")
	)
	(layers
		(0 "F.Cu" signal "TOP")
		(4 "In1.Cu" signal "GND")
		(6 "In2.Cu" signal "VCC")
		(8 "In3.Cu" signal "VCC1")
		(10 "In4.Cu" signal "GND1")
		(12 "In5.Cu" signal "IN1")
		(14 "In6.Cu" signal "GND2")
		(16 "In7.Cu" signal "IN2")
		(18 "In8.Cu" signal "GND3")
		(20 "In9.Cu" signal "IN3")
		(22 "In10.Cu" signal "GND4")
		(24 "In11.Cu" signal "IN4")
		(26 "In12.Cu" signal "GND5")
		(28 "In13.Cu" signal "IN5")
		(30 "In14.Cu" signal "GND6")
		(32 "In15.Cu" signal "IN6")
		(34 "In16.Cu" signal "GND7")
		(2 "B.Cu" signal "BOTTOM")
		(9 "F.Adhes" user "F.Adhesive")
		(11 "B.Adhes" user "B.Adhesive")
		(13 "F.Paste" user "Package Geometry/Pastemask Top")
		(15 "B.Paste" user "Package Geometry/Pastemask Bottom")
		(5 "F.SilkS" user "Ref Des/Silkscreen Top")
		(7 "B.SilkS" user "Ref Des/Silkscreen Bottom")
		(1 "F.Mask" user "Board Geometry/Soldermask Top")
		(3 "B.Mask" user "Board Geometry/Soldermask Bottom")
		(17 "Dwgs.User" user "User.Drawings")
		(19 "Cmts.User" user "User.Comments")
		(21 "Eco1.User" user "User.Eco1")
		(23 "Eco2.User" user "User.Eco2")
		(25 "Edge.Cuts" user "Board Geometry/Outline")
		(27 "Margin" user)
		(31 "F.CrtYd" user "Package Geometry/Place Bound Top")
		(29 "B.CrtYd" user "Package Geometry/Place Bound Bottom")
		(35 "F.Fab" user "Ref Des/Assembly Top")
		(33 "B.Fab" user "Ref Des/Assembly Bottom")
	)
	(footprint ""
		(layer "F.Cu")
		(at 242.587018 -275.602192 135)
		(property "Reference" "C633"
			(at 0 0 135)
			(layer "F.SilkS")
			(hide yes)
			(effects
				(font
					(size 1.27 1.27)
				)
			)
		)
		(property "Value" ""
			(at 0 0 135)
			(layer "F.Fab")
			(effects
				(font
					(size 1.27 1.27)
				)
			)
		)
		(duplicate_pad_numbers_are_jumpers no)
		(fp_line
			(start 0.787389 -0.406267)
			(end 0.787389 0.406267)
			(stroke
				(width 0.1524)
				(type default)
			)
			(layer "F.SilkS")
		)
		(fp_line
			(start 0.787389 0.406267)
			(end -0.787389 0.406267)
			(stroke
				(width 0.1524)
				(type default)
			)
			(layer "F.SilkS")
		)
		(fp_line
			(start -0.787389 -0.406267)
			(end 0.787389 -0.406267)
			(stroke
				(width 0.1524)
				(type default)
			)
			(layer "F.SilkS")
		)
		(fp_line
			(start -0.787389 0.406267)
			(end -0.787389 -0.406267)
			(stroke
				(width 0.1524)
				(type default)
			)
			(layer "F.SilkS")
		)
		(fp_line
			(start 0.679446 -0.30479)
			(end 0.679446 0.30479)
			(stroke
				(width 0.1)
				(type default)
			)
			(layer "F.Fab")
		)
		(fp_line
			(start 0.120515 -0.30479)
			(end 0.679446 -0.30479)
			(stroke
				(width 0.1)
				(type default)
			)
			(layer "F.Fab")
		)
		(fp_line
			(start 0.120695 -0.279466)
			(end 0.120515 -0.30479)
			(stroke
				(width 0.1)
				(type default)
			)
			(layer "F.Fab")
		)
		(fp_line
			(start 0.679446 0.30479)
			(end 0.120515 0.30479)
			(stroke
				(width 0.1)
				(type default)
			)
			(layer "F.Fab")
		)
		(fp_line
			(start -0.120695 -0.304969)
			(end -0.120695 -0.279466)
			(stroke
				(width 0.1)
				(type default)
			)
			(layer "F.Fab")
		)
		(fp_line
			(start -0.120695 -0.279466)
			(end 0.120695 -0.279466)
			(stroke
				(width 0.1)
				(type default)
			)
			(layer "F.Fab")
		)
		(fp_line
			(start 0.120335 0.279466)
			(end -0.120695 0.279466)
			(stroke
				(width 0.1)
				(type default)
			)
			(layer "F.Fab")
		)
		(fp_line
			(start 0.120515 0.30479)
			(end 0.120335 0.279466)
			(stroke
				(width 0.1)
				(type default)
			)
			(layer "F.Fab")
		)
		(fp_line
			(start -0.679446 -0.305149)
			(end -0.120695 -0.304969)
			(stroke
				(width 0.1)
				(type default)
			)
			(layer "F.Fab")
		)
		(fp_line
			(start -0.120695 0.279466)
			(end -0.120515 0.30479)
			(stroke
				(width 0.1)
				(type default)
			)
			(layer "F.Fab")
		)
		(fp_line
			(start -0.120515 0.30479)
			(end -0.679446 0.30479)
			(stroke
				(width 0.1)
				(type default)
			)
			(layer "F.Fab")
		)
		(fp_line
			(start -0.679446 0.30479)
			(end -0.679446 -0.305149)
			(stroke
				(width 0.1)
				(type default)
			)
			(layer "F.Fab")
		)
		(pad "1" smd circle
			(at -0.40005 0 135)
			(size 0 0)
			(layers "F.Cu" "F.Mask" "F.Paste")
			(net "P12V_PEX2_P1V25_VIN_P")
		)
		(pad "2" smd circle
			(at 0.40005 0 135)
			(size 0 0)
			(layers "F.Cu" "F.Mask" "F.Paste")
			(net "P12V_PEX2_P1V25_VIN_N")
		)
	)
	(footprint ""
		(layer "F.Cu")
		(at 343.902792 -240.691162 90)
		(property "Reference" "R3598"
			(at 0 0 90)
			(layer "F.SilkS")
			(hide yes)
			(effects
				(font
					(size 1.27 1.27)
				)
			)
		)
		(property "Value" ""
			(at 0 0 90)
			(layer "F.Fab")
			(effects
				(font
					(size 1.27 1.27)
				)
			)
		)
		(duplicate_pad_numbers_are_jumpers no)
		(fp_line
			(start 0.7874 -0.4064)
			(end 0.7874 0.4064)
			(stroke
				(width 0.1524)
				(type default)
			)
			(layer "F.SilkS")
		)
		(fp_line
			(start -0.7874 -0.4064)
			(end 0.7874 -0.4064)
			(stroke
				(width 0.1524)
				(type default)
			)
			(layer "F.SilkS")
		)
		(fp_line
			(start 0.7874 0.4064)
			(end -0.7874 0.4064)
			(stroke
				(width 0.1524)
				(type default)
			)
			(layer "F.SilkS")
		)
		(fp_line
			(start -0.7874 0.4064)
			(end -0.7874 -0.4064)
			(stroke
				(width 0.1524)
				(type default)
			)
			(layer "F.SilkS")
		)
		(fp_line
			(start -0.12065 -0.305054)
			(end -0.12065 -0.2794)
			(stroke
				(width 0.1)
				(type default)
			)
			(layer "F.Fab")
		)
		(fp_line
			(start -0.67945 -0.305054)
			(end -0.12065 -0.305054)
			(stroke
				(width 0.1)
				(type default)
			)
			(layer "F.Fab")
		)
		(fp_line
			(start 0.67945 -0.3048)
			(end 0.67945 0.3048)
			(stroke
				(width 0.1)
				(type default)
			)
			(layer "F.Fab")
		)
		(fp_line
			(start 0.12065 -0.3048)
			(end 0.67945 -0.3048)
			(stroke
				(width 0.1)
				(type default)
			)
			(layer "F.Fab")
		)
		(fp_line
			(start 0.12065 -0.2794)
			(end 0.12065 -0.3048)
			(stroke
				(width 0.1)
				(type default)
			)
			(layer "F.Fab")
		)
		(fp_line
			(start -0.12065 -0.2794)
			(end 0.12065 -0.2794)
			(stroke
				(width 0.1)
				(type default)
			)
			(layer "F.Fab")
		)
		(fp_line
			(start 0.120396 0.2794)
			(end -0.12065 0.2794)
			(stroke
				(width 0.1)
				(type default)
			)
			(layer "F.Fab")
		)
		(fp_line
			(start -0.12065 0.2794)
			(end -0.12065 0.3048)
			(stroke
				(width 0.1)
				(type default)
			)
			(layer "F.Fab")
		)
		(fp_line
			(start 0.67945 0.3048)
			(end 0.120396 0.3048)
			(stroke
				(width 0.1)
				(type default)
			)
			(layer "F.Fab")
		)
		(fp_line
			(start 0.120396 0.3048)
			(end 0.120396 0.2794)
			(stroke
				(width 0.1)
				(type default)
			)
			(layer "F.Fab")
		)
		(fp_line
			(start -0.12065 0.3048)
			(end -0.67945 0.3048)
			(stroke
				(width 0.1)
				(type default)
			)
			(layer "F.Fab")
		)
		(fp_line
			(start -0.67945 0.3048)
			(end -0.67945 -0.305054)
			(stroke
				(width 0.1)
				(type default)
			)
			(layer "F.Fab")
		)
		(pad "1" smd circle
			(at -0.40005 0 90)
			(size 0 0)
			(layers "F.Cu" "F.Mask" "F.Paste")
			(net "RST_SSD1_PERST_N")
		)
		(pad "2" smd circle
			(at 0.40005 0 90)
			(size 0 0)
			(layers "F.Cu" "F.Mask" "F.Paste")
			(net "RST_SSD1_PERST_R_N")
		)
	)
	(footprint ""
		(layer "F.Cu")
		(at 137.047478 -19.33956)
		(property "Reference" "C3905"
			(at 0 0 0)
			(layer "F.SilkS")
			(hide yes)
			(effects
				(font
					(size 1.27 1.27)
				)
			)
		)
		(property "Value" ""
			(at 0 0 0)
			(layer "F.Fab")
			(effects
				(font
					(size 1.27 1.27)
				)
			)
		)
		(duplicate_pad_numbers_are_jumpers no)
		(fp_line
			(start -0.7874 -0.4064)
			(end 0.7874 -0.4064)
			(stroke
				(width 0.1524)
				(type default)
			)
			(layer "F.SilkS")
		)
		(fp_line
			(start -0.7874 0.4064)
			(end -0.7874 -0.4064)
			(stroke
				(width 0.1524)
				(type default)
			)
			(layer "F.SilkS")
		)
		(fp_line
			(start 0.7874 -0.4064)
			(end 0.7874 0.4064)
			(stroke
				(width 0.1524)
				(type default)
			)
			(layer "F.SilkS")
		)
		(fp_line
			(start 0.7874 0.4064)
			(end -0.7874 0.4064)
			(stroke
				(width 0.1524)
				(type default)
			)
			(layer "F.SilkS")
		)
		(fp_line
			(start -0.67945 -0.305054)
			(end -0.12065 -0.305054)
			(stroke
				(width 0.1)
				(type default)
			)
			(layer "F.Fab")
		)
		(fp_line
			(start -0.67945 0.3048)
			(end -0.67945 -0.305054)
			(stroke
				(width 0.1)
				(type default)
			)
			(layer "F.Fab")
		)
		(fp_line
			(start -0.12065 -0.305054)
			(end -0.12065 -0.2794)
			(stroke
				(width 0.1)
				(type default)
			)
			(layer "F.Fab")
		)
		(fp_line
			(start -0.12065 -0.2794)
			(end 0.12065 -0.2794)
			(stroke
				(width 0.1)
				(type default)
			)
			(layer "F.Fab")
		)
		(fp_line
			(start -0.12065 0.2794)
			(end -0.12065 0.3048)
			(stroke
				(width 0.1)
				(type default)
			)
			(layer "F.Fab")
		)
		(fp_line
			(start -0.12065 0.3048)
			(end -0.67945 0.3048)
			(stroke
				(width 0.1)
				(type default)
			)
			(layer "F.Fab")
		)
		(fp_line
			(start 0.120396 0.2794)
			(end -0.12065 0.2794)
			(stroke
				(width 0.1)
				(type default)
			)
			(layer "F.Fab")
		)
		(fp_line
			(start 0.120396 0.3048)
			(end 0.120396 0.2794)
			(stroke
				(width 0.1)
				(type default)
			)
			(layer "F.Fab")
		)
		(fp_line
			(start 0.12065 -0.3048)
			(end 0.67945 -0.3048)
			(stroke
				(width 0.1)
				(type default)
			)
			(layer "F.Fab")
		)
		(fp_line
			(start 0.12065 -0.2794)
			(end 0.12065 -0.3048)
			(stroke
				(width 0.1)
				(type default)
			)
			(layer "F.Fab")
		)
		(fp_line
			(start 0.67945 -0.3048)
			(end 0.67945 0.3048)
			(stroke
				(width 0.1)
				(type default)
			)
			(layer "F.Fab")
		)
		(fp_line
			(start 0.67945 0.3048)
			(end 0.120396 0.3048)
			(stroke
				(width 0.1)
				(type default)
			)
			(layer "F.Fab")
		)
		(pad "1" smd circle
			(at -0.40005 0)
			(size 0 0)
			(layers "F.Cu" "F.Mask" "F.Paste")
			(net "P12V_SSD4")
		)
		(pad "2" smd circle
			(at 0.40005 0)
			(size 0 0)
			(layers "F.Cu" "F.Mask" "F.Paste")
			(net "GND")
		)
	)
	(footprint ""
		(layer "F.Cu")
		(at 215.985598 -27.092148 -90)
		(property "Reference" "R5745"
			(at 0 0 270)
			(layer "F.SilkS")
			(hide yes)
			(effects
				(font
					(size 1.27 1.27)
				)
			)
		)
		(property "Value" ""
			(at 0 0 270)
			(layer "F.Fab")
			(effects
				(font
					(size 1.27 1.27)
				)
			)
		)
		(duplicate_pad_numbers_are_jumpers no)
		(fp_line
			(start -0.7874 0.4064)
			(end -0.7874 -0.4064)
			(stroke
				(width 0.1524)
				(type default)
			)
			(layer "F.SilkS")
		)
		(fp_line
			(start 0.7874 0.4064)
			(end -0.7874 0.4064)
			(stroke
				(width 0.1524)
				(type default)
			)
			(layer "F.SilkS")
		)
		(fp_line
			(start -0.7874 -0.4064)
			(end 0.7874 -0.4064)
			(stroke
				(width 0.1524)
				(type default)
			)
			(layer "F.SilkS")
		)
		(fp_line
			(start 0.7874 -0.4064)
			(end 0.7874 0.4064)
			(stroke
				(width 0.1524)
				(type default)
			)
			(layer "F.SilkS")
		)
		(fp_line
			(start -0.67945 0.3048)
			(end -0.67945 -0.305054)
			(stroke
				(width 0.1)
				(type default)
			)
			(layer "F.Fab")
		)
		(fp_line
			(start -0.12065 0.3048)
			(end -0.67945 0.3048)
			(stroke
				(width 0.1)
				(type default)
			)
			(layer "F.Fab")
		)
		(fp_line
			(start 0.120396 0.3048)
			(end 0.120396 0.2794)
			(stroke
				(width 0.1)
				(type default)
			)
			(layer "F.Fab")
		)
		(fp_line
			(start 0.67945 0.3048)
			(end 0.120396 0.3048)
			(stroke
				(width 0.1)
				(type default)
			)
			(layer "F.Fab")
		)
		(fp_line
			(start -0.12065 0.2794)
			(end -0.12065 0.3048)
			(stroke
				(width 0.1)
				(type default)
			)
			(layer "F.Fab")
		)
		(fp_line
			(start 0.120396 0.2794)
			(end -0.12065 0.2794)
			(stroke
				(width 0.1)
				(type default)
			)
			(layer "F.Fab")
		)
		(fp_line
			(start -0.12065 -0.2794)
			(end 0.12065 -0.2794)
			(stroke
				(width 0.1)
				(type default)
			)
			(layer "F.Fab")
		)
		(fp_line
			(start 0.12065 -0.2794)
			(end 0.12065 -0.3048)
			(stroke
				(width 0.1)
				(type default)
			)
			(layer "F.Fab")
		)
		(fp_line
			(start 0.12065 -0.3048)
			(end 0.67945 -0.3048)
			(stroke
				(width 0.1)
				(type default)
			)
			(layer "F.Fab")
		)
		(fp_line
			(start 0.67945 -0.3048)
			(end 0.67945 0.3048)
			(stroke
				(width 0.1)
				(type default)
			)
			(layer "F.Fab")
		)
		(fp_line
			(start -0.67945 -0.305054)
			(end -0.12065 -0.305054)
			(stroke
				(width 0.1)
				(type default)
			)
			(layer "F.Fab")
		)
		(fp_line
			(start -0.12065 -0.305054)
			(end -0.12065 -0.2794)
			(stroke
				(width 0.1)
				(type default)
			)
			(layer "F.Fab")
		)
		(pad "1" smd circle
			(at -0.40005 0 270)
			(size 0 0)
			(layers "F.Cu" "F.Mask" "F.Paste")
			(net "P3V3_SSD7")
		)
		(pad "2" smd circle
			(at 0.40005 0 270)
			(size 0 0)
			(layers "F.Cu" "F.Mask" "F.Paste")
			(net "SSD7_LED_ISO_N")
		)
	)
	(footprint ""
		(layer "F.Cu")
		(at 55.8292 -116.5352 180)
		(property "Reference" "R40"
			(at 0 0 180)
			(layer "F.SilkS")
			(hide yes)
			(effects
				(font
					(size 1.27 1.27)
				)
			)
		)
		(property "Value" ""
			(at 0 0 180)
			(layer "F.Fab")
			(effects
				(font
					(size 1.27 1.27)
				)
			)
		)
		(duplicate_pad_numbers_are_jumpers no)
		(fp_line
			(start 0.7874 0.4064)
			(end -0.7874 0.4064)
			(stroke
				(width 0.1524)
				(type default)
			)
			(layer "F.SilkS")
		)
		(fp_line
			(start 0.7874 -0.4064)
			(end 0.7874 0.4064)
			(stroke
				(width 0.1524)
				(type default)
			)
			(layer "F.SilkS")
		)
		(fp_line
			(start -0.7874 0.4064)
			(end -0.7874 -0.4064)
			(stroke
				(width 0.1524)
				(type default)
			)
			(layer "F.SilkS")
		)
		(fp_line
			(start -0.7874 -0.4064)
			(end 0.7874 -0.4064)
			(stroke
				(width 0.1524)
				(type default)
			)
			(layer "F.SilkS")
		)
		(fp_line
			(start 0.67945 0.3048)
			(end 0.120396 0.3048)
			(stroke
				(width 0.1)
				(type default)
			)
			(layer "F.Fab")
		)
		(fp_line
			(start 0.67945 -0.3048)
			(end 0.67945 0.3048)
			(stroke
				(width 0.1)
				(type default)
			)
			(layer "F.Fab")
		)
		(fp_line
			(start 0.12065 -0.2794)
			(end 0.12065 -0.3048)
			(stroke
				(width 0.1)
				(type default)
			)
			(layer "F.Fab")
		)
		(fp_line
			(start 0.12065 -0.3048)
			(end 0.67945 -0.3048)
			(stroke
				(width 0.1)
				(type default)
			)
			(layer "F.Fab")
		)
		(fp_line
			(start 0.120396 0.3048)
			(end 0.120396 0.2794)
			(stroke
				(width 0.1)
				(type default)
			)
			(layer "F.Fab")
		)
		(fp_line
			(start 0.120396 0.2794)
			(end -0.12065 0.2794)
			(stroke
				(width 0.1)
				(type default)
			)
			(layer "F.Fab")
		)
		(fp_line
			(start -0.12065 0.3048)
			(end -0.67945 0.3048)
			(stroke
				(width 0.1)
				(type default)
			)
			(layer "F.Fab")
		)
		(fp_line
			(start -0.12065 0.2794)
			(end -0.12065 0.3048)
			(stroke
				(width 0.1)
				(type default)
			)
			(layer "F.Fab")
		)
		(fp_line
			(start -0.12065 -0.2794)
			(end 0.12065 -0.2794)
			(stroke
				(width 0.1)
				(type default)
			)
			(layer "F.Fab")
		)
		(fp_line
			(start -0.12065 -0.305054)
			(end -0.12065 -0.2794)
			(stroke
				(width 0.1)
				(type default)
			)
			(layer "F.Fab")
		)
		(fp_line
			(start -0.67945 0.3048)
			(end -0.67945 -0.305054)
			(stroke
				(width 0.1)
				(type default)
			)
			(layer "F.Fab")
		)
		(fp_line
			(start -0.67945 -0.305054)
			(end -0.12065 -0.305054)
			(stroke
				(width 0.1)
				(type default)
			)
			(layer "F.Fab")
		)
		(pad "1" smd circle
			(at -0.40005 0 180)
			(size 0 0)
			(layers "F.Cu" "F.Mask" "F.Paste")
			(net "PRSNT_NIC0_N")
		)
		(pad "2" smd circle
			(at 0.40005 0 180)
			(size 0 0)
			(layers "F.Cu" "F.Mask" "F.Paste")
			(net "PRSNTB1_NIC0_N")
		)
	)
	(footprint ""
		(layer "F.Cu")
		(at 341.746586 -282.421584 -90)
		(property "Reference" "PC145"
			(at 0 0 270)
			(layer "F.SilkS")
			(hide yes)
			(effects
				(font
					(size 1.27 1.27)
				)
			)
		)
		(property "Value" ""
			(at 0 0 270)
			(layer "F.Fab")
			(effects
				(font
					(size 1.27 1.27)
				)
			)
		)
		(duplicate_pad_numbers_are_jumpers no)
		(fp_line
			(start -0.7874 0.4064)
			(end -0.7874 -0.4064)
			(stroke
				(width 0.1524)
				(type default)
			)
			(layer "F.SilkS")
		)
		(fp_line
			(start 0.7874 0.4064)
			(end -0.7874 0.4064)
			(stroke
				(width 0.1524)
				(type default)
			)
			(layer "F.SilkS")
		)
		(fp_line
			(start -0.7874 -0.4064)
			(end 0.7874 -0.4064)
			(stroke
				(width 0.1524)
				(type default)
			)
			(layer "F.SilkS")
		)
		(fp_line
			(start 0.7874 -0.4064)
			(end 0.7874 0.4064)
			(stroke
				(width 0.1524)
				(type default)
			)
			(layer "F.SilkS")
		)
		(fp_line
			(start -0.67945 0.3048)
			(end -0.67945 -0.305054)
			(stroke
				(width 0.1)
				(type default)
			)
			(layer "F.Fab")
		)
		(fp_line
			(start -0.12065 0.3048)
			(end -0.67945 0.3048)
			(stroke
				(width 0.1)
				(type default)
			)
			(layer "F.Fab")
		)
		(fp_line
			(start 0.120396 0.3048)
			(end 0.120396 0.2794)
			(stroke
				(width 0.1)
				(type default)
			)
			(layer "F.Fab")
		)
		(fp_line
			(start 0.67945 0.3048)
			(end 0.120396 0.3048)
			(stroke
				(width 0.1)
				(type default)
			)
			(layer "F.Fab")
		)
		(fp_line
			(start -0.12065 0.2794)
			(end -0.12065 0.3048)
			(stroke
				(width 0.1)
				(type default)
			)
			(layer "F.Fab")
		)
		(fp_line
			(start 0.120396 0.2794)
			(end -0.12065 0.2794)
			(stroke
				(width 0.1)
				(type default)
			)
			(layer "F.Fab")
		)
		(fp_line
			(start -0.12065 -0.2794)
			(end 0.12065 -0.2794)
			(stroke
				(width 0.1)
				(type default)
			)
			(layer "F.Fab")
		)
		(fp_line
			(start 0.12065 -0.2794)
			(end 0.12065 -0.3048)
			(stroke
				(width 0.1)
				(type default)
			)
			(layer "F.Fab")
		)
		(fp_line
			(start 0.12065 -0.3048)
			(end 0.67945 -0.3048)
			(stroke
				(width 0.1)
				(type default)
			)
			(layer "F.Fab")
		)
		(fp_line
			(start 0.67945 -0.3048)
			(end 0.67945 0.3048)
			(stroke
				(width 0.1)
				(type default)
			)
			(layer "F.Fab")
		)
		(fp_line
			(start -0.67945 -0.305054)
			(end -0.12065 -0.305054)
			(stroke
				(width 0.1)
				(type default)
			)
			(layer "F.Fab")
		)
		(fp_line
			(start -0.12065 -0.305054)
			(end -0.12065 -0.2794)
			(stroke
				(width 0.1)
				(type default)
			)
			(layer "F.Fab")
		)
		(pad "1" smd circle
			(at -0.40005 0 270)
			(size 0 0)
			(layers "F.Cu" "F.Mask" "F.Paste")
			(net "P0V8_PEX2_VCC1")
		)
		(pad "2" smd circle
			(at 0.40005 0 270)
			(size 0 0)
			(layers "F.Cu" "F.Mask" "F.Paste")
			(net "GND")
		)
	)
)
